(kicad_pcb
	(version 20260206)
	(generator "pcbnew")
	(generator_version "10.0")
	(general
		(thickness 1.6)
		(legacy_teardrops no)
	)
	(paper "A4")
	(title_block
		(title "01162023_DA0F0TEBIF0_F0T_Expander_BD_F_brd_V02_OCP.brd")
		(comment 1 "Grand Teton / footprints 774-779 of 9728")
	)
	(layers
		(0 "F.Cu" signal "TOP")
		(4 "In1.Cu" signal "GND")
		(6 "In2.Cu" signal "VCC")
		(8 "In3.Cu" signal "VCC1")
		(10 "In4.Cu" signal "GND1")
		(12 "In5.Cu" signal "IN1")
		(14 "In6.Cu" signal "GND2")
		(16 "In7.Cu" signal "IN2")
		(18 "In8.Cu" signal "GND3")
		(20 "In9.Cu" signal "IN3")
		(22 "In10.Cu" signal "GND4")
		(24 "In11.Cu" signal "IN4")
		(26 "In12.Cu" signal "GND5")
		(28 "In13.Cu" signal "IN5")
		(30 "In14.Cu" signal "GND6")
		(32 "In15.Cu" signal "IN6")
		(34 "In16.Cu" signal "GND7")
		(2 "B.Cu" signal "BOTTOM")
		(9 "F.Adhes" user "F.Adhesive")
		(11 "B.Adhes" user "B.Adhesive")
		(13 "F.Paste" user "Package Geometry/Pastemask Top")
		(15 "B.Paste" user "Package Geometry/Pastemask Bottom")
		(5 "F.SilkS" user "Ref Des/Silkscreen Top")
		(7 "B.SilkS" user "Ref Des/Silkscreen Bottom")
		(1 "F.Mask" user "Board Geometry/Soldermask Top")
		(3 "B.Mask" user "Board Geometry/Soldermask Bottom")
		(17 "Dwgs.User" user "User.Drawings")
		(19 "Cmts.User" user "User.Comments")
		(21 "Eco1.User" user "User.Eco1")
		(23 "Eco2.User" user "User.Eco2")
		(25 "Edge.Cuts" user "Board Geometry/Outline")
		(27 "Margin" user)
		(31 "F.CrtYd" user "Package Geometry/Place Bound Top")
		(29 "B.CrtYd" user "Package Geometry/Place Bound Bottom")
		(35 "F.Fab" user "Ref Des/Assembly Top")
		(33 "B.Fab" user "Ref Des/Assembly Bottom")
	)
	(footprint ""
		(layer "F.Cu")
		(at 134.026656 -25.432004 -90)
		(property "Reference" "C969"
			(at 0 0 270)
			(layer "F.SilkS")
			(hide yes)
			(effects
				(font
					(size 1.27 1.27)
				)
			)
		)
		(property "Value" ""
			(at 0 0 270)
			(layer "F.Fab")
			(effects
				(font
					(size 1.27 1.27)
				)
			)
		)
		(duplicate_pad_numbers_are_jumpers no)
		(fp_line
			(start -0.7874 0.4064)
			(end -0.7874 -0.4064)
			(stroke
				(width 0.1524)
				(type default)
			)
			(layer "F.SilkS")
		)
		(fp_line
			(start 0.7874 0.4064)
			(end -0.7874 0.4064)
			(stroke
				(width 0.1524)
				(type default)
			)
			(layer "F.SilkS")
		)
		(fp_line
			(start -0.7874 -0.4064)
			(end 0.7874 -0.4064)
			(stroke
				(width 0.1524)
				(type default)
			)
			(layer "F.SilkS")
		)
		(fp_line
			(start 0.7874 -0.4064)
			(end 0.7874 0.4064)
			(stroke
				(width 0.1524)
				(type default)
			)
			(layer "F.SilkS")
		)
		(fp_line
			(start -0.67945 0.3048)
			(end -0.67945 -0.305054)
			(stroke
				(width 0.1)
				(type default)
			)
			(layer "F.Fab")
		)
		(fp_line
			(start -0.12065 0.3048)
			(end -0.67945 0.3048)
			(stroke
				(width 0.1)
				(type default)
			)
			(layer "F.Fab")
		)
		(fp_line
			(start 0.120396 0.3048)
			(end 0.120396 0.2794)
			(stroke
				(width 0.1)
				(type default)
			)
			(layer "F.Fab")
		)
		(fp_line
			(start 0.67945 0.3048)
			(end 0.120396 0.3048)
			(stroke
				(width 0.1)
				(type default)
			)
			(layer "F.Fab")
		)
		(fp_line
			(start -0.12065 0.2794)
			(end -0.12065 0.3048)
			(stroke
				(width 0.1)
				(type default)
			)
			(layer "F.Fab")
		)
		(fp_line
			(start 0.120396 0.2794)
			(end -0.12065 0.2794)
			(stroke
				(width 0.1)
				(type default)
			)
			(layer "F.Fab")
		)
		(fp_line
			(start -0.12065 -0.2794)
			(end 0.12065 -0.2794)
			(stroke
				(width 0.1)
				(type default)
			)
			(layer "F.Fab")
		)
		(fp_line
			(start 0.12065 -0.2794)
			(end 0.12065 -0.3048)
			(stroke
				(width 0.1)
				(type default)
			)
			(layer "F.Fab")
		)
		(fp_line
			(start 0.12065 -0.3048)
			(end 0.67945 -0.3048)
			(stroke
				(width 0.1)
				(type default)
			)
			(layer "F.Fab")
		)
		(fp_line
			(start 0.67945 -0.3048)
			(end 0.67945 0.3048)
			(stroke
				(width 0.1)
				(type default)
			)
			(layer "F.Fab")
		)
		(fp_line
			(start -0.67945 -0.305054)
			(end -0.12065 -0.305054)
			(stroke
				(width 0.1)
				(type default)
			)
			(layer "F.Fab")
		)
		(fp_line
			(start -0.12065 -0.305054)
			(end -0.12065 -0.2794)
			(stroke
				(width 0.1)
				(type default)
			)
			(layer "F.Fab")
		)
		(pad "1" smd circle
			(at -0.40005 0 270)
			(size 0 0)
			(layers "F.Cu" "F.Mask" "F.Paste")
			(net "GND")
		)
		(pad "2" smd circle
			(at 0.40005 0 270)
			(size 0 0)
			(layers "F.Cu" "F.Mask" "F.Paste")
			(net "P3V3_SSD4")
		)
	)
	(footprint ""
		(layer "F.Cu")
		(at 220.36786 -56.353456)
		(property "Reference" "C2868"
			(at 0 0 0)
			(layer "F.SilkS")
			(hide yes)
			(effects
				(font
					(size 1.27 1.27)
				)
			)
		)
		(property "Value" ""
			(at 0 0 0)
			(layer "F.Fab")
			(effects
				(font
					(size 1.27 1.27)
				)
			)
		)
		(duplicate_pad_numbers_are_jumpers no)
		(fp_line
			(start -0.7874 -0.4064)
			(end 0.7874 -0.4064)
			(stroke
				(width 0.1524)
				(type default)
			)
			(layer "F.SilkS")
		)
		(fp_line
			(start -0.7874 0.4064)
			(end -0.7874 -0.4064)
			(stroke
				(width 0.1524)
				(type default)
			)
			(layer "F.SilkS")
		)
		(fp_line
			(start 0.7874 -0.4064)
			(end 0.7874 0.4064)
			(stroke
				(width 0.1524)
				(type default)
			)
			(layer "F.SilkS")
		)
		(fp_line
			(start 0.7874 0.4064)
			(end -0.7874 0.4064)
			(stroke
				(width 0.1524)
				(type default)
			)
			(layer "F.SilkS")
		)
		(fp_line
			(start -0.67945 -0.305054)
			(end -0.12065 -0.305054)
			(stroke
				(width 0.1)
				(type default)
			)
			(layer "F.Fab")
		)
		(fp_line
			(start -0.67945 0.3048)
			(end -0.67945 -0.305054)
			(stroke
				(width 0.1)
				(type default)
			)
			(layer "F.Fab")
		)
		(fp_line
			(start -0.12065 -0.305054)
			(end -0.12065 -0.2794)
			(stroke
				(width 0.1)
				(type default)
			)
			(layer "F.Fab")
		)
		(fp_line
			(start -0.12065 -0.2794)
			(end 0.12065 -0.2794)
			(stroke
				(width 0.1)
				(type default)
			)
			(layer "F.Fab")
		)
		(fp_line
			(start -0.12065 0.2794)
			(end -0.12065 0.3048)
			(stroke
				(width 0.1)
				(type default)
			)
			(layer "F.Fab")
		)
		(fp_line
			(start -0.12065 0.3048)
			(end -0.67945 0.3048)
			(stroke
				(width 0.1)
				(type default)
			)
			(layer "F.Fab")
		)
		(fp_line
			(start 0.120396 0.2794)
			(end -0.12065 0.2794)
			(stroke
				(width 0.1)
				(type default)
			)
			(layer "F.Fab")
		)
		(fp_line
			(start 0.120396 0.3048)
			(end 0.120396 0.2794)
			(stroke
				(width 0.1)
				(type default)
			)
			(layer "F.Fab")
		)
		(fp_line
			(start 0.12065 -0.3048)
			(end 0.67945 -0.3048)
			(stroke
				(width 0.1)
				(type default)
			)
			(layer "F.Fab")
		)
		(fp_line
			(start 0.12065 -0.2794)
			(end 0.12065 -0.3048)
			(stroke
				(width 0.1)
				(type default)
			)
			(layer "F.Fab")
		)
		(fp_line
			(start 0.67945 -0.3048)
			(end 0.67945 0.3048)
			(stroke
				(width 0.1)
				(type default)
			)
			(layer "F.Fab")
		)
		(fp_line
			(start 0.67945 0.3048)
			(end 0.120396 0.3048)
			(stroke
				(width 0.1)
				(type default)
			)
			(layer "F.Fab")
		)
		(pad "1" smd circle
			(at -0.40005 0)
			(size 0 0)
			(layers "F.Cu" "F.Mask" "F.Paste")
			(net "SSD7_PWR_EN_R")
		)
		(pad "2" smd circle
			(at 0.40005 0)
			(size 0 0)
			(layers "F.Cu" "F.Mask" "F.Paste")
			(net "GND")
		)
	)
	(footprint ""
		(layer "F.Cu")
		(at 134.76859 -149.313392 -90)
		(property "Reference" "U81"
			(at 0.012192 -2.44348 90)
			(unlocked yes)
			(layer "F.SilkS")
			(effects
				(font
					(size 0.7874 0.5842)
					(thickness 0.1524)
				)
			)
		)
		(property "Value" ""
			(at 0 0 270)
			(layer "F.Fab")
			(effects
				(font
					(size 1.27 1.27)
				)
			)
		)
		(duplicate_pad_numbers_are_jumpers no)
		(fp_line
			(start -1.500124 1.500124)
			(end -1.500124 1.004062)
			(stroke
				(width 0.1524)
				(type default)
			)
			(layer "F.SilkS")
		)
		(fp_line
			(start -1.004062 1.500124)
			(end -1.500124 1.500124)
			(stroke
				(width 0.1524)
				(type default)
			)
			(layer "F.SilkS")
		)
		(fp_line
			(start 1.500124 1.500124)
			(end 1.004062 1.500124)
			(stroke
				(width 0.1524)
				(type default)
			)
			(layer "F.SilkS")
		)
		(fp_line
			(start 1.500124 1.004062)
			(end 1.500124 1.500124)
			(stroke
				(width 0.1524)
				(type default)
			)
			(layer "F.SilkS")
		)
		(fp_line
			(start -1.500124 -1.004062)
			(end -1.500124 -1.500124)
			(stroke
				(width 0.1524)
				(type default)
			)
			(layer "F.SilkS")
		)
		(fp_line
			(start -1.500124 -1.500124)
			(end -1.004062 -1.500124)
			(stroke
				(width 0.1524)
				(type default)
			)
			(layer "F.SilkS")
		)
		(fp_line
			(start 1.004062 -1.500124)
			(end 1.500124 -1.500124)
			(stroke
				(width 0.1524)
				(type default)
			)
			(layer "F.SilkS")
		)
		(fp_line
			(start 1.500124 -1.500124)
			(end 1.500124 -1.004062)
			(stroke
				(width 0.1524)
				(type default)
			)
			(layer "F.SilkS")
		)
		(fp_poly
			(pts
				(xy -1.963166 -2.07772) (xy -2.681732 -1.359408) (xy -1.60401 -1.000252)
			)
			(stroke
				(width 0)
				(type default)
			)
			(fill yes)
			(layer "F.SilkS")
		)
		(fp_line
			(start -1.500124 1.500124)
			(end -1.500124 -1.500124)
			(stroke
				(width 0.1)
				(type default)
			)
			(layer "F.Fab")
		)
		(fp_line
			(start 1.500124 1.500124)
			(end -1.500124 1.500124)
			(stroke
				(width 0.1)
				(type default)
			)
			(layer "F.Fab")
		)
		(fp_line
			(start -1.500124 -1.500124)
			(end 1.500124 -1.500124)
			(stroke
				(width 0.1)
				(type default)
			)
			(layer "F.Fab")
		)
		(fp_line
			(start 1.500124 -1.500124)
			(end 1.500124 1.500124)
			(stroke
				(width 0.1)
				(type default)
			)
			(layer "F.Fab")
		)
		(fp_poly
			(pts
				(xy -2.847848 -1.258062) (xy -2.847848 -0.242062) (xy -1.831848 -0.750062)
			)
			(stroke
				(width 0)
				(type default)
			)
			(fill yes)
			(layer "F.Fab")
		)
		(pad "1" smd rect
			(at -1.400048 -0.750062 180)
			(size 0.2286 0.6096)
			(layers "F.Cu" "F.Mask" "F.Paste")
			(net "NIC2_ADC_A1")
		)
		(pad "2" smd rect
			(at -1.400048 -0.249936 180)
			(size 0.2286 0.6096)
			(layers "F.Cu" "F.Mask" "F.Paste")
			(net "NIC2_ADC_A0")
		)
		(pad "3" smd rect
			(at -1.400048 0.249936 180)
			(size 0.2286 0.6096)
			(layers "F.Cu" "F.Mask" "F.Paste")
			(net "NIC2_ADC_ALERT_N")
		)
		(pad "4" smd rect
			(at -1.400048 0.750062 180)
			(size 0.2286 0.6096)
			(layers "F.Cu" "F.Mask" "F.Paste")
			(net "SMB_NIC2_ADC_SDA")
		)
		(pad "5" smd rect
			(at -0.750062 1.400048 270)
			(size 0.2286 0.6096)
			(layers "F.Cu" "F.Mask" "F.Paste")
			(net "SMB_NIC2_ADC_SCL")
		)
		(pad "6" smd rect
			(at -0.249936 1.400048 270)
			(size 0.2286 0.6096)
			(layers "F.Cu" "F.Mask" "F.Paste")
			(net "Net_8654")
		)
		(pad "7" smd rect
			(at 0.249936 1.400048 270)
			(size 0.2286 0.6096)
			(layers "F.Cu" "F.Mask" "F.Paste")
			(net "Net_8653")
		)
		(pad "8" smd rect
			(at 0.750062 1.400048 270)
			(size 0.2286 0.6096)
			(layers "F.Cu" "F.Mask" "F.Paste")
			(net "Net_8652")
		)
		(pad "9" smd rect
			(at 1.400048 0.750062 180)
			(size 0.2286 0.6096)
			(layers "F.Cu" "F.Mask" "F.Paste")
			(net "P3V3_AUX")
		)
		(pad "10" smd rect
			(at 1.400048 0.249936 180)
			(size 0.2286 0.6096)
			(layers "F.Cu" "F.Mask" "F.Paste")
			(net "GND")
		)
		(pad "11" smd rect
			(at 1.400048 -0.249936 180)
			(size 0.2286 0.6096)
			(layers "F.Cu" "F.Mask" "F.Paste")
			(net "P12V_NIC2_R")
		)
		(pad "12" smd rect
			(at 1.400048 -0.750062 180)
			(size 0.2286 0.6096)
			(layers "F.Cu" "F.Mask" "F.Paste")
			(net "P12V_NIC2_VIN_N")
		)
		(pad "13" smd rect
			(at 0.750062 -1.400048 270)
			(size 0.2286 0.6096)
			(layers "F.Cu" "F.Mask" "F.Paste")
			(net "P12V_NIC2_VIN_P")
		)
		(pad "14" smd rect
			(at 0.249936 -1.400048 270)
			(size 0.2286 0.6096)
			(layers "F.Cu" "F.Mask" "F.Paste")
			(net "Net_8651")
		)
		(pad "15" smd rect
			(at -0.249936 -1.400048 270)
			(size 0.2286 0.6096)
			(layers "F.Cu" "F.Mask" "F.Paste")
			(net "Net_8650")
		)
		(pad "16" smd rect
			(at -0.750062 -1.400048 270)
			(size 0.2286 0.6096)
			(layers "F.Cu" "F.Mask" "F.Paste")
			(net "Net_8649")
		)
		(pad "TH" smd rect
			(at 0 0 270)
			(size 1.7018 1.7018)
			(layers "F.Cu" "F.Mask" "F.Paste")
			(net "GND")
		)
		(zone
			(layer "F.Cu")
			(hatch none 0.5)
			(connect_pads
				(clearance 0)
			)
			(min_thickness 0.25)
			(keepout
				(tracks not_allowed)
				(vias allowed)
				(pads allowed)
				(copperpour not_allowed)
				(footprints allowed)
			)
			(placement
				(enabled no)
				(sheetname "")
			)
			(fill
				(thermal_gap 0.5)
				(thermal_bridge_width 0.5)
				(island_removal_mode 0)
			)
			(polygon
				(pts
					(xy 134.79399 -150.35784) (xy 135.813038 -150.35784) (xy 135.813038 -148.268944) (xy 133.724142 -148.268944)
					(xy 133.724142 -150.35784) (xy 134.76859 -150.35784) (xy 134.76859 -150.215092) (xy 133.86689 -150.215092)
					(xy 133.86689 -148.411692) (xy 135.67029 -148.411692) (xy 135.67029 -150.215092) (xy 134.79399 -150.215092)
				)
			)
		)
	)
	(footprint ""
		(layer "F.Cu")
		(at 399.14322 -350.098614 90)
		(property "Reference" "C734"
			(at 0 0 90)
			(layer "F.SilkS")
			(hide yes)
			(effects
				(font
					(size 1.27 1.27)
				)
			)
		)
		(property "Value" ""
			(at 0 0 90)
			(layer "F.Fab")
			(effects
				(font
					(size 1.27 1.27)
				)
			)
		)
		(duplicate_pad_numbers_are_jumpers no)
		(fp_line
			(start 0.299974 -0.150114)
			(end 0.299974 0.150114)
			(stroke
				(width 0.1)
				(type default)
			)
			(layer "F.Fab")
		)
		(fp_line
			(start -0.299974 -0.150114)
			(end 0.299974 -0.150114)
			(stroke
				(width 0.1)
				(type default)
			)
			(layer "F.Fab")
		)
		(fp_line
			(start 0.299974 0.150114)
			(end -0.299974 0.150114)
			(stroke
				(width 0.1)
				(type default)
			)
			(layer "F.Fab")
		)
		(fp_line
			(start -0.299974 0.150114)
			(end -0.299974 -0.150114)
			(stroke
				(width 0.1)
				(type default)
			)
			(layer "F.Fab")
		)
		(pad "1" smd rect
			(at -0.2667 0 90)
			(size 0.3048 0.381)
			(layers "F.Cu" "F.Mask" "F.Paste")
			(net "P5E_PEX3_STN5_TX_DP<93>")
		)
		(pad "2" smd rect
			(at 0.2667 0 90)
			(size 0.3048 0.381)
			(layers "F.Cu" "F.Mask" "F.Paste")
			(net "P5E_PEX3_STN5_TX_C_DP<93>")
		)
	)
	(footprint ""
		(layer "F.Cu")
		(at 149.080728 -379.396498)
		(property "Reference" "R1838"
			(at 0 0 0)
			(layer "F.SilkS")
			(hide yes)
			(effects
				(font
					(size 1.27 1.27)
				)
			)
		)
		(property "Value" ""
			(at 0 0 0)
			(layer "F.Fab")
			(effects
				(font
					(size 1.27 1.27)
				)
			)
		)
		(duplicate_pad_numbers_are_jumpers no)
		(fp_line
			(start -0.7874 -0.4064)
			(end 0.7874 -0.4064)
			(stroke
				(width 0.1524)
				(type default)
			)
			(layer "F.SilkS")
		)
		(fp_line
			(start -0.7874 0.4064)
			(end -0.7874 -0.4064)
			(stroke
				(width 0.1524)
				(type default)
			)
			(layer "F.SilkS")
		)
		(fp_line
			(start 0.7874 -0.4064)
			(end 0.7874 0.4064)
			(stroke
				(width 0.1524)
				(type default)
			)
			(layer "F.SilkS")
		)
		(fp_line
			(start 0.7874 0.4064)
			(end -0.7874 0.4064)
			(stroke
				(width 0.1524)
				(type default)
			)
			(layer "F.SilkS")
		)
		(fp_line
			(start -0.67945 -0.305054)
			(end -0.12065 -0.305054)
			(stroke
				(width 0.1)
				(type default)
			)
			(layer "F.Fab")
		)
		(fp_line
			(start -0.67945 0.3048)
			(end -0.67945 -0.305054)
			(stroke
				(width 0.1)
				(type default)
			)
			(layer "F.Fab")
		)
		(fp_line
			(start -0.12065 -0.305054)
			(end -0.12065 -0.2794)
			(stroke
				(width 0.1)
				(type default)
			)
			(layer "F.Fab")
		)
		(fp_line
			(start -0.12065 -0.2794)
			(end 0.12065 -0.2794)
			(stroke
				(width 0.1)
				(type default)
			)
			(layer "F.Fab")
		)
		(fp_line
			(start -0.12065 0.2794)
			(end -0.12065 0.3048)
			(stroke
				(width 0.1)
				(type default)
			)
			(layer "F.Fab")
		)
		(fp_line
			(start -0.12065 0.3048)
			(end -0.67945 0.3048)
			(stroke
				(width 0.1)
				(type default)
			)
			(layer "F.Fab")
		)
		(fp_line
			(start 0.120396 0.2794)
			(end -0.12065 0.2794)
			(stroke
				(width 0.1)
				(type default)
			)
			(layer "F.Fab")
		)
		(fp_line
			(start 0.120396 0.3048)
			(end 0.120396 0.2794)
			(stroke
				(width 0.1)
				(type default)
			)
			(layer "F.Fab")
		)
		(fp_line
			(start 0.12065 -0.3048)
			(end 0.67945 -0.3048)
			(stroke
				(width 0.1)
				(type default)
			)
			(layer "F.Fab")
		)
		(fp_line
			(start 0.12065 -0.2794)
			(end 0.12065 -0.3048)
			(stroke
				(width 0.1)
				(type default)
			)
			(layer "F.Fab")
		)
		(fp_line
			(start 0.67945 -0.3048)
			(end 0.67945 0.3048)
			(stroke
				(width 0.1)
				(type default)
			)
			(layer "F.Fab")
		)
		(fp_line
			(start 0.67945 0.3048)
			(end 0.120396 0.3048)
			(stroke
				(width 0.1)
				(type default)
			)
			(layer "F.Fab")
		)
		(pad "1" smd circle
			(at -0.40005 0)
			(size 0 0)
			(layers "F.Cu" "F.Mask" "F.Paste")
			(net "GPU_FPGA_EROT_FATALERR_R_N")
		)
		(pad "2" smd circle
			(at 0.40005 0)
			(size 0 0)
			(layers "F.Cu" "F.Mask" "F.Paste")
			(net "GPU_FPGA_EROT_FATALERR_N")
		)
	)
	(footprint ""
		(layer "F.Cu")
		(at 339.75294 -80.607662 90)
		(property "Reference" "R1175"
			(at 0 0 90)
			(layer "F.SilkS")
			(hide yes)
			(effects
				(font
					(size 1.27 1.27)
				)
			)
		)
		(property "Value" ""
			(at 0 0 90)
			(layer "F.Fab")
			(effects
				(font
					(size 1.27 1.27)
				)
			)
		)
		(duplicate_pad_numbers_are_jumpers no)
		(fp_line
			(start 0.7874 0.4064)
			(end -0.7874 0.4064)
			(stroke
				(width 0.1524)
				(type default)
			)
			(layer "F.SilkS")
		)
		(fp_line
			(start -0.12065 -0.305054)
			(end -0.12065 -0.2794)
			(stroke
				(width 0.1)
				(type default)
			)
			(layer "F.Fab")
		)
		(fp_line
			(start -0.67945 -0.305054)
			(end -0.12065 -0.305054)
			(stroke
				(width 0.1)
				(type default)
			)
			(layer "F.Fab")
		)
		(fp_line
			(start 0.67945 -0.3048)
			(end 0.67945 0.3048)
			(stroke
				(width 0.1)
				(type default)
			)
			(layer "F.Fab")
		)
		(fp_line
			(start 0.12065 -0.3048)
			(end 0.67945 -0.3048)
			(stroke
				(width 0.1)
				(type default)
			)
			(layer "F.Fab")
		)
		(fp_line
			(start 0.12065 -0.2794)
			(end 0.12065 -0.3048)
			(stroke
				(width 0.1)
				(type default)
			)
			(layer "F.Fab")
		)
		(fp_line
			(start -0.12065 -0.2794)
			(end 0.12065 -0.2794)
			(stroke
				(width 0.1)
				(type default)
			)
			(layer "F.Fab")
		)
		(fp_line
			(start 0.120396 0.2794)
			(end -0.12065 0.2794)
			(stroke
				(width 0.1)
				(type default)
			)
			(layer "F.Fab")
		)
		(fp_line
			(start -0.12065 0.2794)
			(end -0.12065 0.3048)
			(stroke
				(width 0.1)
				(type default)
			)
			(layer "F.Fab")
		)
		(fp_line
			(start 0.67945 0.3048)
			(end 0.120396 0.3048)
			(stroke
				(width 0.1)
				(type default)
			)
			(layer "F.Fab")
		)
		(fp_line
			(start 0.120396 0.3048)
			(end 0.120396 0.2794)
			(stroke
				(width 0.1)
				(type default)
			)
			(layer "F.Fab")
		)
		(fp_line
			(start -0.12065 0.3048)
			(end -0.67945 0.3048)
			(stroke
				(width 0.1)
				(type default)
			)
			(layer "F.Fab")
		)
		(fp_line
			(start -0.67945 0.3048)
			(end -0.67945 -0.305054)
			(stroke
				(width 0.1)
				(type default)
			)
			(layer "F.Fab")
		)
		(pad "1" smd circle
			(at -0.40005 0 90)
			(size 0 0)
			(layers "F.Cu" "F.Mask" "F.Paste")
			(net "CLK_100M_DB800ZL_SSD10_R_DN")
		)
		(pad "2" smd circle
			(at 0.40005 0 90)
			(size 0 0)
			(layers "F.Cu" "F.Mask" "F.Paste")
			(net "CLK_100M_DB800ZL_SSD10_DN")
		)
	)
)
